(kicad_pcb
	(version 20241229)
	(generator "pcbnew")
	(generator_version "9.0")
	(general
		(thickness 1.552)
		(legacy_teardrops no)
	)
	(paper "A4")
	(title_block
		(date "2023-07-25")
		(rev "1.1.4")
		(comment 9 "footprints 100-104 of 379")
	)
	(layers
		(0 "F.Cu" signal)
		(4 "In1.Cu" signal)
		(6 "In2.Cu" signal)
		(8 "In3.Cu" signal)
		(10 "In4.Cu" signal)
		(12 "In5.Cu" signal)
		(14 "In6.Cu" signal)
		(2 "B.Cu" signal)
		(9 "F.Adhes" user "F.Adhesive")
		(11 "B.Adhes" user "B.Adhesive")
		(13 "F.Paste" user)
		(15 "B.Paste" user)
		(5 "F.SilkS" user "F.Silkscreen")
		(7 "B.SilkS" user "B.Silkscreen")
		(1 "F.Mask" user)
		(3 "B.Mask" user)
		(17 "Dwgs.User" user "User.Drawings")
		(19 "Cmts.User" user "User.Comments")
		(21 "Eco1.User" user "User.Eco1")
		(23 "Eco2.User" user "User.Eco2")
		(25 "Edge.Cuts" user)
		(27 "Margin" user)
		(31 "F.CrtYd" user "F.Courtyard")
		(29 "B.CrtYd" user "B.Courtyard")
		(35 "F.Fab" user)
		(33 "B.Fab" user)
	)
	(footprint "antmicro-footprints:R_0402_1005Metric"
		(layer "F.Cu")
		(at 146.34 116.55 180)
		(descr "Resistor SMD 0402")
		(tags "resistor SMD 0402")
		(property "Reference" "R20"
			(at -0.89 -0.29 180)
			(layer "F.SilkS")
			(effects
				(font
					(size 0.65 0.65)
					(thickness 0.15)
				)
				(justify left bottom)
			)
		)
		(property "Value" "R_0R_0402"
			(at 0 1.4 180)
			(layer "F.Fab")
			(hide yes)
			(effects
				(font
					(size 0.7 0.7)
					(thickness 0.15)
				)
				(justify left bottom)
			)
		)
		(property "Datasheet" "https://industrial.panasonic.com/cdbs/www-data/pdf/RDA0000/AOA0000C301.pdf"
			(at 0 0 180)
			(layer "F.Fab")
			(hide yes)
			(effects
				(font
					(size 1.27 1.27)
					(thickness 0.15)
				)
			)
		)
		(property "Description" "SMD Chip Resistor, Jumper, 0 ohm, 100 mW, 0402 [1005 Metric], Thick Film, General Purpose"
			(at 0 0 180)
			(layer "F.Fab")
			(hide yes)
			(effects
				(font
					(size 1.27 1.27)
					(thickness 0.15)
				)
			)
		)
		(property "Author" "Antmicro"
			(at 292.68 233.1 0)
			(layer "F.Fab")
			(hide yes)
			(effects
				(font
					(size 1 1)
					(thickness 0.15)
				)
			)
		)
		(property "Current" "1A"
			(at 292.68 233.1 0)
			(layer "F.Fab")
			(hide yes)
			(effects
				(font
					(size 1 1)
					(thickness 0.15)
				)
			)
		)
		(property "License" "Apache-2.0"
			(at 292.68 233.1 0)
			(layer "F.Fab")
			(hide yes)
			(effects
				(font
					(size 1 1)
					(thickness 0.15)
				)
			)
		)
		(property "MPN" "ERJ2GE0R00X"
			(at 292.68 233.1 0)
			(layer "F.Fab")
			(hide yes)
			(effects
				(font
					(size 1 1)
					(thickness 0.15)
				)
			)
		)
		(property "Manufacturer" "Panasonic"
			(at 292.68 233.1 0)
			(layer "F.Fab")
			(hide yes)
			(effects
				(font
					(size 1 1)
					(thickness 0.15)
				)
			)
		)
		(property "Tolerance" "~"
			(at 292.68 233.1 0)
			(layer "F.Fab")
			(hide yes)
			(effects
				(font
					(size 1 1)
					(thickness 0.15)
				)
			)
		)
		(property "Val" "0R"
			(at 292.68 233.1 0)
			(layer "F.Fab")
			(hide yes)
			(effects
				(font
					(size 1 1)
					(thickness 0.15)
				)
			)
		)
		(sheetname "/Power Supply/")
		(sheetfile "supply.kicad_sch")
		(attr smd)
		(fp_rect
			(start -0.925 -0.47)
			(end 0.925 0.47)
			(stroke
				(width 0.05)
				(type default)
			)
			(fill no)
			(layer "F.CrtYd")
		)
		(fp_rect
			(start -0.5 -0.25)
			(end 0.5 0.25)
			(stroke
				(width 0.15)
				(type solid)
			)
			(fill no)
			(layer "F.Fab")
		)
		(fp_text user "Author: Antmicro"
			(at -0.95 4.169 180)
			(layer "F.Fab")
			(effects
				(font
					(size 0.7 0.7)
					(thickness 0.15)
				)
				(justify left bottom)
			)
		)
		(fp_text user "${REFERENCE}"
			(at -0.95 3.168 180)
			(layer "F.Fab")
			(effects
				(font
					(size 0.7 0.7)
					(thickness 0.15)
				)
				(justify left bottom)
			)
		)
		(fp_text user "License: Apache-2.0"
			(at -0.95 5.169 180)
			(layer "F.Fab")
			(effects
				(font
					(size 0.7 0.7)
					(thickness 0.15)
				)
				(justify left bottom)
			)
		)
		(pad "1" smd roundrect
			(at -0.48 0 180)
			(size 0.59 0.64)
			(layers "F.Cu" "F.Mask" "F.Paste")
			(roundrect_rratio 0.25)
			(net 2 "+3V3")
			(pintype "passive")
		)
		(pad "2" smd roundrect
			(at 0.48 0 180)
			(size 0.59 0.64)
			(layers "F.Cu" "F.Mask" "F.Paste")
			(roundrect_rratio 0.25)
			(net 265 "Net-(U9-V_{IN})")
			(pintype "passive")
		)
	)
	(footprint "antmicro-footprints:R_0402_1005Metric"
		(layer "F.Cu")
		(at 133.83 113.15 180)
		(descr "Resistor SMD 0402")
		(tags "resistor SMD 0402")
		(property "Reference" "R72"
			(at 3.2 0.01 180)
			(layer "F.SilkS")
			(effects
				(font
					(size 0.65 0.65)
					(thickness 0.15)
				)
				(justify left bottom)
			)
		)
		(property "Value" "R_100R_0402"
			(at 0 1.4 180)
			(layer "F.Fab")
			(hide yes)
			(effects
				(font
					(size 0.7 0.7)
					(thickness 0.15)
				)
				(justify left bottom)
			)
		)
		(property "Datasheet" "https://www.bourns.com/docs/product-datasheets/cr.pdf"
			(at 0 0 180)
			(layer "F.Fab")
			(hide yes)
			(effects
				(font
					(size 1.27 1.27)
					(thickness 0.15)
				)
			)
		)
		(property "Description" "SMD Chip Resistor, 100 ohm, ± 1%, 62.5 mW, 0402 [1005 Metric], Thick Film, General Purpose"
			(at 0 0 180)
			(layer "F.Fab")
			(hide yes)
			(effects
				(font
					(size 1.27 1.27)
					(thickness 0.15)
				)
			)
		)
		(property "Author" "Antmicro"
			(at 267.66 226.3 0)
			(layer "F.Fab")
			(hide yes)
			(effects
				(font
					(size 1 1)
					(thickness 0.15)
				)
			)
		)
		(property "License" "Apache-2.0"
			(at 267.66 226.3 0)
			(layer "F.Fab")
			(hide yes)
			(effects
				(font
					(size 1 1)
					(thickness 0.15)
				)
			)
		)
		(property "MPN" "CR0402-FX-1000GLF"
			(at 267.66 226.3 0)
			(layer "F.Fab")
			(hide yes)
			(effects
				(font
					(size 1 1)
					(thickness 0.15)
				)
			)
		)
		(property "Manufacturer" "Bourns"
			(at 267.66 226.3 0)
			(layer "F.Fab")
			(hide yes)
			(effects
				(font
					(size 1 1)
					(thickness 0.15)
				)
			)
		)
		(property "Tolerance" "1%"
			(at 267.66 226.3 0)
			(layer "F.Fab")
			(hide yes)
			(effects
				(font
					(size 1 1)
					(thickness 0.15)
				)
			)
		)
		(property "Val" "100R"
			(at 267.66 226.3 0)
			(layer "F.Fab")
			(hide yes)
			(effects
				(font
					(size 1 1)
					(thickness 0.15)
				)
			)
		)
		(sheetname "/FPGA/")
		(sheetfile "fpga.kicad_sch")
		(attr smd)
		(fp_rect
			(start -0.925 -0.47)
			(end 0.925 0.47)
			(stroke
				(width 0.05)
				(type default)
			)
			(fill no)
			(layer "F.CrtYd")
		)
		(fp_rect
			(start -0.5 -0.25)
			(end 0.5 0.25)
			(stroke
				(width 0.15)
				(type solid)
			)
			(fill no)
			(layer "F.Fab")
		)
		(fp_text user "License: Apache-2.0"
			(at -0.95 5.169 180)
			(layer "F.Fab")
			(effects
				(font
					(size 0.7 0.7)
					(thickness 0.15)
				)
				(justify left bottom)
			)
		)
		(fp_text user "Author: Antmicro"
			(at -0.95 4.169 180)
			(layer "F.Fab")
			(effects
				(font
					(size 0.7 0.7)
					(thickness 0.15)
				)
				(justify left bottom)
			)
		)
		(fp_text user "${REFERENCE}"
			(at -0.95 3.168 180)
			(layer "F.Fab")
			(effects
				(font
					(size 0.7 0.7)
					(thickness 0.15)
				)
				(justify left bottom)
			)
		)
		(pad "1" smd roundrect
			(at -0.48 0 180)
			(size 0.59 0.64)
			(layers "F.Cu" "F.Mask" "F.Paste")
			(roundrect_rratio 0.25)
			(net 381 "Net-(C80-Pad2)")
			(pintype "passive")
		)
		(pad "2" smd roundrect
			(at 0.48 0 180)
			(size 0.59 0.64)
			(layers "F.Cu" "F.Mask" "F.Paste")
			(roundrect_rratio 0.25)
			(net 281 "Net-(R72-Pad2)")
			(pintype "passive")
		)
	)
	(footprint "antmicro-footprints:C_0402_1005Metric"
		(layer "F.Cu")
		(at 109.3 98.7 180)
		(descr "Capacitor SMD 0402")
		(tags "capacitor SMD 0402")
		(property "Reference" "C125"
			(at -0.93 -0.34 180)
			(layer "F.SilkS")
			(effects
				(font
					(size 0.65 0.65)
					(thickness 0.15)
				)
				(justify left bottom)
			)
		)
		(property "Value" "C_100n_0402"
			(at 0 1.4 180)
			(layer "F.Fab")
			(hide yes)
			(effects
				(font
					(size 0.7 0.7)
					(thickness 0.15)
				)
				(justify left bottom)
			)
		)
		(property "Datasheet" "https://www.murata.com/products/productdetail?partno=GRM155R61H104KE14%23"
			(at 0 0 180)
			(layer "F.Fab")
			(hide yes)
			(effects
				(font
					(size 1.27 1.27)
					(thickness 0.15)
				)
			)
		)
		(property "Description" "SMD Multilayer Ceramic Capacitor, 0.1 µF, 50 V, 0402 [1005 Metric], ± 10%, X5R, GRM Series"
			(at 0 0 180)
			(layer "F.Fab")
			(hide yes)
			(effects
				(font
					(size 1.27 1.27)
					(thickness 0.15)
				)
			)
		)
		(property "Author" "Antmicro"
			(at 218.6 197.4 0)
			(layer "F.Fab")
			(hide yes)
			(effects
				(font
					(size 1 1)
					(thickness 0.15)
				)
			)
		)
		(property "Dielectric" "X5R"
			(at 218.6 197.4 0)
			(layer "F.Fab")
			(hide yes)
			(effects
				(font
					(size 1 1)
					(thickness 0.15)
				)
			)
		)
		(property "License" "Apache-2.0"
			(at 218.6 197.4 0)
			(layer "F.Fab")
			(hide yes)
			(effects
				(font
					(size 1 1)
					(thickness 0.15)
				)
			)
		)
		(property "MPN" "GRM155R61H104KE14D"
			(at 218.6 197.4 0)
			(layer "F.Fab")
			(hide yes)
			(effects
				(font
					(size 1 1)
					(thickness 0.15)
				)
			)
		)
		(property "Manufacturer" "Murata"
			(at 218.6 197.4 0)
			(layer "F.Fab")
			(hide yes)
			(effects
				(font
					(size 1 1)
					(thickness 0.15)
				)
			)
		)
		(property "Val" "100n"
			(at 218.6 197.4 0)
			(layer "F.Fab")
			(hide yes)
			(effects
				(font
					(size 1 1)
					(thickness 0.15)
				)
			)
		)
		(property "Voltage" "50V"
			(at 218.6 197.4 0)
			(layer "F.Fab")
			(hide yes)
			(effects
				(font
					(size 1 1)
					(thickness 0.15)
				)
			)
		)
		(sheetname "/FPGA/")
		(sheetfile "fpga.kicad_sch")
		(attr smd)
		(fp_rect
			(start -0.925 -0.47)
			(end 0.925 0.47)
			(stroke
				(width 0.05)
				(type default)
			)
			(fill no)
			(layer "F.CrtYd")
		)
		(fp_line
			(start 0.504 0.248)
			(end -0.494 0.248)
			(stroke
				(width 0.15)
				(type solid)
			)
			(layer "F.Fab")
		)
		(fp_line
			(start 0.504 -0.25)
			(end 0.504 0.248)
			(stroke
				(width 0.15)
				(type solid)
			)
			(layer "F.Fab")
		)
		(fp_line
			(start -0.494 0.248)
			(end -0.494 -0.25)
			(stroke
				(width 0.15)
				(type solid)
			)
			(layer "F.Fab")
		)
		(fp_line
			(start -0.494 -0.25)
			(end 0.504 -0.25)
			(stroke
				(width 0.15)
				(type solid)
			)
			(layer "F.Fab")
		)
		(fp_text user "${REFERENCE}"
			(at -0.939 4.599 180)
			(layer "F.Fab")
			(effects
				(font
					(size 0.7 0.7)
					(thickness 0.15)
				)
				(justify left bottom)
			)
		)
		(fp_text user "License: Apache-2.0"
			(at -0.939 5.799 180)
			(layer "F.Fab")
			(effects
				(font
					(size 0.7 0.7)
					(thickness 0.15)
				)
				(justify left bottom)
			)
		)
		(fp_text user "Author: Antmicro"
			(at -0.939 3.399 180)
			(layer "F.Fab")
			(effects
				(font
					(size 0.7 0.7)
					(thickness 0.15)
				)
				(justify left bottom)
			)
		)
		(pad "1" smd roundrect
			(at -0.48 0 180)
			(size 0.59 0.64)
			(layers "F.Cu" "F.Mask" "F.Paste")
			(roundrect_rratio 0.25)
			(net 2 "+3V3")
			(pintype "passive")
		)
		(pad "2" smd roundrect
			(at 0.48 0 180)
			(size 0.59 0.64)
			(layers "F.Cu" "F.Mask" "F.Paste")
			(roundrect_rratio 0.25)
			(net 1 "GND")
			(pintype "passive")
		)
	)
	(footprint "antmicro-footprints:R_0402_1005Metric"
		(layer "F.Cu")
		(at 100.94 115.185 90)
		(descr "Resistor SMD 0402")
		(tags "resistor SMD 0402")
		(property "Reference" "R94"
			(at 0.895 0.39 90)
			(layer "F.SilkS")
			(effects
				(font
					(size 0.65 0.65)
					(thickness 0.15)
				)
				(justify left bottom)
			)
		)
		(property "Value" "R_0R_0402"
			(at 0 1.4 90)
			(layer "F.Fab")
			(hide yes)
			(effects
				(font
					(size 0.7 0.7)
					(thickness 0.15)
				)
				(justify left bottom)
			)
		)
		(property "Datasheet" "https://industrial.panasonic.com/cdbs/www-data/pdf/RDA0000/AOA0000C301.pdf"
			(at 0 0 90)
			(layer "F.Fab")
			(hide yes)
			(effects
				(font
					(size 1.27 1.27)
					(thickness 0.15)
				)
			)
		)
		(property "Description" "SMD Chip Resistor, Jumper, 0 ohm, 100 mW, 0402 [1005 Metric], Thick Film, General Purpose"
			(at 0 0 90)
			(layer "F.Fab")
			(hide yes)
			(effects
				(font
					(size 1.27 1.27)
					(thickness 0.15)
				)
			)
		)
		(property "Author" "Antmicro"
			(at 216.125 14.245 0)
			(layer "F.Fab")
			(hide yes)
			(effects
				(font
					(size 1 1)
					(thickness 0.15)
				)
			)
		)
		(property "Current" "1A"
			(at 216.125 14.245 0)
			(layer "F.Fab")
			(hide yes)
			(effects
				(font
					(size 1 1)
					(thickness 0.15)
				)
			)
		)
		(property "License" "Apache-2.0"
			(at 216.125 14.245 0)
			(layer "F.Fab")
			(hide yes)
			(effects
				(font
					(size 1 1)
					(thickness 0.15)
				)
			)
		)
		(property "MPN" "ERJ2GE0R00X"
			(at 216.125 14.245 0)
			(layer "F.Fab")
			(hide yes)
			(effects
				(font
					(size 1 1)
					(thickness 0.15)
				)
			)
		)
		(property "Manufacturer" "Panasonic"
			(at 216.125 14.245 0)
			(layer "F.Fab")
			(hide yes)
			(effects
				(font
					(size 1 1)
					(thickness 0.15)
				)
			)
		)
		(property "Tolerance" "~"
			(at 216.125 14.245 0)
			(layer "F.Fab")
			(hide yes)
			(effects
				(font
					(size 1 1)
					(thickness 0.15)
				)
			)
		)
		(property "Val" "0R"
			(at 216.125 14.245 0)
			(layer "F.Fab")
			(hide yes)
			(effects
				(font
					(size 1 1)
					(thickness 0.15)
				)
			)
		)
		(sheetname "/FPGA/")
		(sheetfile "fpga.kicad_sch")
		(attr smd)
		(fp_rect
			(start -0.925 -0.47)
			(end 0.925 0.47)
			(stroke
				(width 0.05)
				(type default)
			)
			(fill no)
			(layer "F.CrtYd")
		)
		(fp_rect
			(start -0.5 -0.25)
			(end 0.5 0.25)
			(stroke
				(width 0.15)
				(type solid)
			)
			(fill no)
			(layer "F.Fab")
		)
		(fp_text user "Author: Antmicro"
			(at -0.95 4.169 90)
			(layer "F.Fab")
			(effects
				(font
					(size 0.7 0.7)
					(thickness 0.15)
				)
				(justify left bottom)
			)
		)
		(fp_text user "${REFERENCE}"
			(at -0.95 3.168 90)
			(layer "F.Fab")
			(effects
				(font
					(size 0.7 0.7)
					(thickness 0.15)
				)
				(justify left bottom)
			)
		)
		(fp_text user "License: Apache-2.0"
			(at -0.95 5.169 90)
			(layer "F.Fab")
			(effects
				(font
					(size 0.7 0.7)
					(thickness 0.15)
				)
				(justify left bottom)
			)
		)
		(pad "1" smd roundrect
			(at -0.48 0 90)
			(size 0.59 0.64)
			(layers "F.Cu" "F.Mask" "F.Paste")
			(roundrect_rratio 0.25)
			(net 136 "Net-(J7-Pad6)")
			(pintype "passive")
		)
		(pad "2" smd roundrect
			(at 0.48 0 90)
			(size 0.59 0.64)
			(layers "F.Cu" "F.Mask" "F.Paste")
			(roundrect_rratio 0.25)
			(net 171 "TDO")
			(pintype "passive")
		)
	)
	(footprint "antmicro-footprints:R_0603_1608Metric"
		(layer "F.Cu")
		(at 165.53 87.4 90)
		(descr "Resistor SMD 0603")
		(tags "resistor SMD 0603")
		(property "Reference" "R108"
			(at -2.14 -2.1 180)
			(layer "F.SilkS")
			(effects
				(font
					(size 0.65 0.65)
					(thickness 0.15)
				)
				(justify left bottom)
			)
		)
		(property "Value" "R_15k_0603"
			(at 0 1.6 90)
			(layer "F.Fab")
			(hide yes)
			(effects
				(font
					(size 0.7 0.7)
					(thickness 0.15)
				)
				(justify left bottom)
			)
		)
		(property "Datasheet" "https://www.bourns.com/docs/product-datasheets/cr.pdf"
			(at 0 0 90)
			(layer "F.Fab")
			(hide yes)
			(effects
				(font
					(size 1.27 1.27)
					(thickness 0.15)
				)
			)
		)
		(property "Description" "SMD Chip Resistor, 15 kohm, ± 1%, 100 mW, 0603 [1608 Metric], Thick Film, General Purpose"
			(at 0 0 90)
			(layer "F.Fab")
			(hide yes)
			(effects
				(font
					(size 1.27 1.27)
					(thickness 0.15)
				)
			)
		)
		(property "Author" "Antmicro"
			(at 252.93 -78.13 0)
			(layer "F.Fab")
			(hide yes)
			(effects
				(font
					(size 1 1)
					(thickness 0.15)
				)
			)
		)
		(property "License" "Apache-2.0"
			(at 252.93 -78.13 0)
			(layer "F.Fab")
			(hide yes)
			(effects
				(font
					(size 1 1)
					(thickness 0.15)
				)
			)
		)
		(property "MPN" "CR0603-FX-1502ELF"
			(at 252.93 -78.13 0)
			(layer "F.Fab")
			(hide yes)
			(effects
				(font
					(size 1 1)
					(thickness 0.15)
				)
			)
		)
		(property "Manufacturer" "Bourns"
			(at 252.93 -78.13 0)
			(layer "F.Fab")
			(hide yes)
			(effects
				(font
					(size 1 1)
					(thickness 0.15)
				)
			)
		)
		(property "Tolerance" "1%"
			(at 252.93 -78.13 0)
			(layer "F.Fab")
			(hide yes)
			(effects
				(font
					(size 1 1)
					(thickness 0.15)
				)
			)
		)
		(property "Val" "15k"
			(at 252.93 -78.13 0)
			(layer "F.Fab")
			(hide yes)
			(effects
				(font
					(size 1 1)
					(thickness 0.15)
				)
			)
		)
		(sheetname "/Peripherals/")
		(sheetfile "peripherals.kicad_sch")
		(attr smd)
		(fp_line
			(start -0.15 -0.4)
			(end 0.15 -0.4)
			(stroke
				(width 0.15)
				(type solid)
			)
			(layer "F.SilkS")
		)
		(fp_line
			(start -0.15 0.4)
			(end 0.15 0.4)
			(stroke
				(width 0.15)
				(type solid)
			)
			(layer "F.SilkS")
		)
		(fp_rect
			(start -1.25 -0.65)
			(end 1.25 0.65)
			(stroke
				(width 0.05)
				(type solid)
			)
			(fill no)
			(layer "F.CrtYd")
		)
		(fp_rect
			(start -0.8 -0.4)
			(end 0.8 0.4)
			(stroke
				(width 0.15)
				(type solid)
			)
			(fill no)
			(layer "F.Fab")
		)
		(fp_text user "${REFERENCE}"
			(at -1.25 3.898 90)
			(layer "F.Fab")
			(effects
				(font
					(size 0.7 0.7)
					(thickness 0.15)
				)
				(justify left bottom)
			)
		)
		(fp_text user "Author: Antmicro"
			(at -1.25 4.9 90)
			(layer "F.Fab")
			(effects
				(font
					(size 0.7 0.7)
					(thickness 0.15)
				)
				(justify left bottom)
			)
		)
		(fp_text user "License: Apache-2.0"
			(at -1.25 5.9 90)
			(layer "F.Fab")
			(effects
				(font
					(size 0.7 0.7)
					(thickness 0.15)
				)
				(justify left bottom)
			)
		)
		(pad "1" smd roundrect
			(at -0.7 0 90)
			(size 0.8 1)
			(layers "F.Cu" "F.Mask" "F.Paste")
			(roundrect_rratio 0.2)
			(net 1 "GND")
			(pintype "passive")
		)
		(pad "2" smd roundrect
			(at 0.7 0 90)
			(size 0.8 1)
			(layers "F.Cu" "F.Mask" "F.Paste")
			(roundrect_rratio 0.2)
			(net 354 "Net-(U14-ILIM)")
			(pintype "passive")
		)
	)
)
